# S9S_MB_2U (Grand Teton) — schematic netlist excerpt (pin names and nets, part order shuffled) for the footprints in the layout excerpt that follows; sources: Cadence DE-HDL packaged netlist, KiCad conversion of 03242023_DA0F0TMBIJ0_F0T_Motherboard_J_brd_V01_OCP.brd

R4395  Q_RES  100 1% CHIP  pkg 0402LF  page 121 : A = PVNN_TERM_CPU0 ; B = H_CPU0_THERMTRIP_LVC1_R_N
R3158  Q_RES  33.2 1% CHIP  pkg 0402LF  page 164 : A = FM_SMB_CPU1_ALERT ; B = FM_SMB_PEHPCPU1_PCIE_ALERT_N

(kicad_pcb
	(version 20260206)
	(generator "pcbnew")
	(generator_version "10.0")
	(general
		(thickness 1.6)
		(legacy_teardrops no)
	)
	(paper "A4")
	(title_block
		(title "03242023_DA0F0TMBIJ0_F0T_Motherboard_J_brd_V01_OCP.brd")
		(comment 1 "Grand Teton / footprints 1819-1820 of 6105")
	)
	(layers
		(0 "F.Cu" signal "TOP")
		(4 "In1.Cu" signal "GND")
		(6 "In2.Cu" signal "IN1")
		(8 "In3.Cu" signal "GND1")
		(10 "In4.Cu" signal "IN2")
		(12 "In5.Cu" signal "GND2")
		(14 "In6.Cu" signal "IN3")
		(16 "In7.Cu" signal "GND3")
		(18 "In8.Cu" signal "VCC")
		(20 "In9.Cu" signal "VCC1")
		(22 "In10.Cu" signal "GND4")
		(24 "In11.Cu" signal "IN4")
		(26 "In12.Cu" signal "GND5")
		(28 "In13.Cu" signal "IN5")
		(30 "In14.Cu" signal "GND6")
		(32 "In15.Cu" signal "IN6")
		(34 "In16.Cu" signal "GND7")
		(2 "B.Cu" signal "BOTTOM")
		(9 "F.Adhes" user "F.Adhesive")
		(11 "B.Adhes" user "B.Adhesive")
		(13 "F.Paste" user "Package Geometry/Pastemask Top")
		(15 "B.Paste" user "Package Geometry/Pastemask Bottom")
		(5 "F.SilkS" user "Ref Des/Silkscreen Top")
		(7 "B.SilkS" user "Ref Des/Silkscreen Bottom")
		(1 "F.Mask" user "Board Geometry/Soldermask Top")
		(3 "B.Mask" user "Board Geometry/Soldermask Bottom")
		(17 "Dwgs.User" user "User.Drawings")
		(19 "Cmts.User" user "User.Comments")
		(21 "Eco1.User" user "User.Eco1")
		(23 "Eco2.User" user "User.Eco2")
		(25 "Edge.Cuts" user "Board Geometry/Outline")
		(27 "Margin" user)
		(31 "F.CrtYd" user "Package Geometry/Place Bound Top")
		(29 "B.CrtYd" user "Package Geometry/Place Bound Bottom")
		(35 "F.Fab" user "Ref Des/Assembly Top")
		(33 "B.Fab" user "Ref Des/Assembly Bottom")
	)
	(footprint ""
		(layer "F.Cu")
		(at 134.21106 -127.056388 180)
		(property "Reference" "R3158"
			(at 0 0 180)
			(layer "F.SilkS")
			(hide yes)
			(effects
				(font
					(size 1.27 1.27)
				)
			)
		)
		(property "Value" ""
			(at 0 0 180)
			(layer "F.Fab")
			(effects
				(font
					(size 1.27 1.27)
				)
			)
		)
		(duplicate_pad_numbers_are_jumpers no)
		(fp_line
			(start 0.7874 0.4064)
			(end -0.7874 0.4064)
			(stroke
				(width 0.1524)
				(type default)
			)
			(layer "F.SilkS")
		)
		(fp_line
			(start 0.7874 -0.4064)
			(end 0.7874 0.4064)
			(stroke
				(width 0.1524)
				(type default)
			)
			(layer "F.SilkS")
		)
		(fp_line
			(start -0.7874 0.4064)
			(end -0.7874 -0.4064)
			(stroke
				(width 0.1524)
				(type default)
			)
			(layer "F.SilkS")
		)
		(fp_line
			(start -0.7874 -0.4064)
			(end 0.7874 -0.4064)
			(stroke
				(width 0.1524)
				(type default)
			)
			(layer "F.SilkS")
		)
		(fp_line
			(start 0.67945 0.3048)
			(end 0.120396 0.3048)
			(stroke
				(width 0.1)
				(type default)
			)
			(layer "F.Fab")
		)
		(fp_line
			(start 0.67945 -0.3048)
			(end 0.67945 0.3048)
			(stroke
				(width 0.1)
				(type default)
			)
			(layer "F.Fab")
		)
		(fp_line
			(start 0.12065 -0.2794)
			(end 0.12065 -0.3048)
			(stroke
				(width 0.1)
				(type default)
			)
			(layer "F.Fab")
		)
		(fp_line
			(start 0.12065 -0.3048)
			(end 0.67945 -0.3048)
			(stroke
				(width 0.1)
				(type default)
			)
			(layer "F.Fab")
		)
		(fp_line
			(start 0.120396 0.3048)
			(end 0.120396 0.2794)
			(stroke
				(width 0.1)
				(type default)
			)
			(layer "F.Fab")
		)
		(fp_line
			(start 0.120396 0.2794)
			(end -0.12065 0.2794)
			(stroke
				(width 0.1)
				(type default)
			)
			(layer "F.Fab")
		)
		(fp_line
			(start -0.12065 0.3048)
			(end -0.67945 0.3048)
			(stroke
				(width 0.1)
				(type default)
			)
			(layer "F.Fab")
		)
		(fp_line
			(start -0.12065 0.2794)
			(end -0.12065 0.3048)
			(stroke
				(width 0.1)
				(type default)
			)
			(layer "F.Fab")
		)
		(fp_line
			(start -0.12065 -0.2794)
			(end 0.12065 -0.2794)
			(stroke
				(width 0.1)
				(type default)
			)
			(layer "F.Fab")
		)
		(fp_line
			(start -0.12065 -0.305054)
			(end -0.12065 -0.2794)
			(stroke
				(width 0.1)
				(type default)
			)
			(layer "F.Fab")
		)
		(fp_line
			(start -0.67945 0.3048)
			(end -0.67945 -0.305054)
			(stroke
				(width 0.1)
				(type default)
			)
			(layer "F.Fab")
		)
		(fp_line
			(start -0.67945 -0.305054)
			(end -0.12065 -0.305054)
			(stroke
				(width 0.1)
				(type default)
			)
			(layer "F.Fab")
		)
		(pad "1" smd circle
			(at -0.40005 0 180)
			(size 0 0)
			(layers "F.Cu" "F.Mask" "F.Paste")
			(net "FM_SMB_CPU1_ALERT")
		)
		(pad "2" smd circle
			(at 0.40005 0 180)
			(size 0 0)
			(layers "F.Cu" "F.Mask" "F.Paste")
			(net "FM_SMB_PEHPCPU1_PCIE_ALERT_N")
		)
	)
	(footprint ""
		(layer "F.Cu")
		(at 120.57888 -92.674948 -90)
		(property "Reference" "R4395"
			(at 0 0 270)
			(layer "F.SilkS")
			(hide yes)
			(effects
				(font
					(size 1.27 1.27)
				)
			)
		)
		(property "Value" ""
			(at 0 0 270)
			(layer "F.Fab")
			(effects
				(font
					(size 1.27 1.27)
				)
			)
		)
		(duplicate_pad_numbers_are_jumpers no)
		(fp_line
			(start -0.7874 0.4064)
			(end -0.7874 -0.4064)
			(stroke
				(width 0.1524)
				(type default)
			)
			(layer "F.SilkS")
		)
		(fp_line
			(start 0.7874 0.4064)
			(end -0.7874 0.4064)
			(stroke
				(width 0.1524)
				(type default)
			)
			(layer "F.SilkS")
		)
		(fp_line
			(start -0.7874 -0.4064)
			(end 0.7874 -0.4064)
			(stroke
				(width 0.1524)
				(type default)
			)
			(layer "F.SilkS")
		)
		(fp_line
			(start 0.7874 -0.4064)
			(end 0.7874 0.4064)
			(stroke
				(width 0.1524)
				(type default)
			)
			(layer "F.SilkS")
		)
		(fp_line
			(start -0.67945 0.3048)
			(end -0.67945 -0.305054)
			(stroke
				(width 0.1)
				(type default)
			)
			(layer "F.Fab")
		)
		(fp_line
			(start -0.12065 0.3048)
			(end -0.67945 0.3048)
			(stroke
				(width 0.1)
				(type default)
			)
			(layer "F.Fab")
		)
		(fp_line
			(start 0.120396 0.3048)
			(end 0.120396 0.2794)
			(stroke
				(width 0.1)
				(type default)
			)
			(layer "F.Fab")
		)
		(fp_line
			(start 0.67945 0.3048)
			(end 0.120396 0.3048)
			(stroke
				(width 0.1)
				(type default)
			)
			(layer "F.Fab")
		)
		(fp_line
			(start -0.12065 0.2794)
			(end -0.12065 0.3048)
			(stroke
				(width 0.1)
				(type default)
			)
			(layer "F.Fab")
		)
		(fp_line
			(start 0.120396 0.2794)
			(end -0.12065 0.2794)
			(stroke
				(width 0.1)
				(type default)
			)
			(layer "F.Fab")
		)
		(fp_line
			(start -0.12065 -0.2794)
			(end 0.12065 -0.2794)
			(stroke
				(width 0.1)
				(type default)
			)
			(layer "F.Fab")
		)
		(fp_line
			(start 0.12065 -0.2794)
			(end 0.12065 -0.3048)
			(stroke
				(width 0.1)
				(type default)
			)
			(layer "F.Fab")
		)
		(fp_line
			(start 0.12065 -0.3048)
			(end 0.67945 -0.3048)
			(stroke
				(width 0.1)
				(type default)
			)
			(layer "F.Fab")
		)
		(fp_line
			(start 0.67945 -0.3048)
			(end 0.67945 0.3048)
			(stroke
				(width 0.1)
				(type default)
			)
			(layer "F.Fab")
		)
		(fp_line
			(start -0.67945 -0.305054)
			(end -0.12065 -0.305054)
			(stroke
				(width 0.1)
				(type default)
			)
			(layer "F.Fab")
		)
		(fp_line
			(start -0.12065 -0.305054)
			(end -0.12065 -0.2794)
			(stroke
				(width 0.1)
				(type default)
			)
			(layer "F.Fab")
		)
		(pad "1" smd circle
			(at -0.40005 0 270)
			(size 0 0)
			(layers "F.Cu" "F.Mask" "F.Paste")
			(net "PVNN_TERM_CPU0")
		)
		(pad "2" smd circle
			(at 0.40005 0 270)
			(size 0 0)
			(layers "F.Cu" "F.Mask" "F.Paste")
			(net "H_CPU0_THERMTRIP_LVC1_R_N")
		)
	)
)
